(kicad_pcb
	(version 20260206)
	(generator "pcbnew")
	(generator_version "10.0")
	(general
		(thickness 1.6)
		(legacy_teardrops no)
	)
	(paper "A4")
	(title_block
		(title "v1-pdb — T6M_PDB_D_0927_0900.brd")
		(comment 1 "Open CloudServer (Microsoft) / footprints 202-204 of 321")
	)
	(layers
		(0 "F.Cu" signal "TOP")
		(4 "In1.Cu" signal "GND")
		(6 "In2.Cu" signal "IN1")
		(8 "In3.Cu" signal "VCC")
		(10 "In4.Cu" signal "VCC1")
		(12 "In5.Cu" signal "IN2")
		(14 "In6.Cu" signal "GND1")
		(2 "B.Cu" signal "BOTTOM")
		(9 "F.Adhes" user "F.Adhesive")
		(11 "B.Adhes" user "B.Adhesive")
		(13 "F.Paste" user "Package Geometry/Pastemask Top")
		(15 "B.Paste" user "Package Geometry/Pastemask Bottom")
		(5 "F.SilkS" user "Ref Des/Silkscreen Top")
		(7 "B.SilkS" user "Ref Des/Silkscreen Bottom")
		(1 "F.Mask" user "Board Geometry/Soldermask Top")
		(3 "B.Mask" user "Board Geometry/Soldermask Bottom")
		(17 "Dwgs.User" user "User.Drawings")
		(19 "Cmts.User" user "User.Comments")
		(21 "Eco1.User" user "User.Eco1")
		(23 "Eco2.User" user "User.Eco2")
		(25 "Edge.Cuts" user "Board Geometry/Outline")
		(27 "Margin" user)
		(31 "F.CrtYd" user "Package Geometry/Place Bound Top")
		(29 "B.CrtYd" user "Package Geometry/Place Bound Bottom")
		(35 "F.Fab" user "Ref Des/Assembly Top")
		(33 "B.Fab" user "Ref Des/Assembly Bottom")
	)
	(footprint ""
		(layer "F.Cu")
		(at 13.71473 -131.750054 180)
		(property "Reference" "J29"
			(at -5.524754 4.01066 0)
			(unlocked yes)
			(layer "F.SilkS")
			(effects
				(font
					(size 0.7874 0.5842)
					(thickness 0.1524)
				)
				(justify left)
			)
		)
		(property "Value" ""
			(at 0 0 180)
			(layer "F.Fab")
			(effects
				(font
					(size 1.27 1.27)
				)
			)
		)
		(duplicate_pad_numbers_are_jumpers no)
		(fp_line
			(start 12.644882 12.899898)
			(end -3.754882 12.899898)
			(stroke
				(width 0.1524)
				(type default)
			)
			(layer "F.SilkS")
		)
		(fp_line
			(start 12.644882 3.7846)
			(end 12.644882 12.899898)
			(stroke
				(width 0.1524)
				(type default)
			)
			(layer "F.SilkS")
		)
		(fp_line
			(start 12.644882 -3.800094)
			(end 12.644882 1.2192)
			(stroke
				(width 0.1524)
				(type default)
			)
			(layer "F.SilkS")
		)
		(fp_line
			(start -3.754882 12.899898)
			(end -3.754882 3.7846)
			(stroke
				(width 0.1524)
				(type default)
			)
			(layer "F.SilkS")
		)
		(fp_line
			(start -3.754882 1.2192)
			(end -3.754882 -3.800094)
			(stroke
				(width 0.1524)
				(type default)
			)
			(layer "F.SilkS")
		)
		(fp_line
			(start -3.754882 -3.800094)
			(end 12.644882 -3.800094)
			(stroke
				(width 0.1524)
				(type default)
			)
			(layer "F.SilkS")
		)
		(fp_poly
			(pts
				(xy -4.125214 0) (xy -5.806186 0.840486) (xy -5.806186 -0.840486)
			)
			(stroke
				(width 0)
				(type default)
			)
			(fill yes)
			(layer "F.SilkS")
		)
		(fp_poly
			(pts
				(xy 7.5184 11.176) (xy 11.4808 11.176) (xy 11.4808 9.7282) (xy 7.5184 9.7282)
			)
			(stroke
				(width 0)
				(type default)
			)
			(fill no)
			(layer "B.CrtYd")
		)
		(fp_poly
			(pts
				(xy -2.591562 11.176) (xy 1.370838 11.176) (xy 1.370838 9.7282) (xy -2.591562 9.7282)
			)
			(stroke
				(width 0)
				(type default)
			)
			(fill no)
			(layer "B.CrtYd")
		)
		(fp_poly
			(pts
				(xy 9.627362 -3.256026) (xy 9.627362 -1.808226) (xy 8.357362 -1.808226) (xy 8.357362 0.731774) (xy -0.735838 0.731774)
				(xy -0.735838 -0.741426) (xy 0.534162 -0.741426) (xy 0.534162 -3.256026)
			)
			(stroke
				(width 0)
				(type default)
			)
			(fill no)
			(layer "B.CrtYd")
		)
		(fp_poly
			(pts
				(arc
					(start 11.088116 2.500122)
					(mid 13.551916 2.500122)
					(end 11.088116 2.500122)
				)
			)
			(stroke
				(width 0)
				(type default)
			)
			(fill no)
			(layer "B.CrtYd")
		)
		(fp_poly
			(pts
				(arc
					(start -4.661916 2.500122)
					(mid -2.198116 2.500122)
					(end -4.661916 2.500122)
				)
			)
			(stroke
				(width 0)
				(type default)
			)
			(fill no)
			(layer "B.CrtYd")
		)
		(fp_poly
			(pts
				(arc
					(start 8.3058 6.35)
					(mid 12.0142 6.35)
					(end 8.3058 6.35)
				)
			)
			(stroke
				(width 0)
				(type default)
			)
			(fill no)
			(layer "B.CrtYd")
		)
		(fp_poly
			(pts
				(arc
					(start -3.1242 6.35)
					(mid 0.5842 6.35)
					(end -3.1242 6.35)
				)
			)
			(stroke
				(width 0)
				(type default)
			)
			(fill no)
			(layer "B.CrtYd")
		)
		(fp_poly
			(pts
				(xy -3.754882 12.899898)
				(arc
					(start -3.754882 3.688334)
					(mid -4.661838 2.500089)
					(end -3.754882 1.311656)
				)
				(xy -3.754882 -3.800094) (xy 12.644882 -3.800094)
				(arc
					(start 12.644882 1.311656)
					(mid 13.552083 2.500089)
					(end 12.644882 3.688334)
				)
				(xy 12.644882 12.899898)
			)
			(stroke
				(width 0)
				(type default)
			)
			(fill no)
			(layer "F.CrtYd")
		)
		(fp_line
			(start 12.644882 12.899898)
			(end -3.754882 12.899898)
			(stroke
				(width 0.1)
				(type default)
			)
			(layer "F.Fab")
		)
		(fp_line
			(start 12.644882 -3.800094)
			(end 12.644882 12.899898)
			(stroke
				(width 0.1)
				(type default)
			)
			(layer "F.Fab")
		)
		(fp_line
			(start -3.754882 12.899898)
			(end -3.754882 -3.800094)
			(stroke
				(width 0.1)
				(type default)
			)
			(layer "F.Fab")
		)
		(fp_line
			(start -3.754882 -3.800094)
			(end 12.644882 -3.800094)
			(stroke
				(width 0.1)
				(type default)
			)
			(layer "F.Fab")
		)
		(fp_poly
			(pts
				(xy -4.125214 0) (xy -5.806186 0.840486) (xy -5.806186 -0.840486)
			)
			(stroke
				(width 0)
				(type default)
			)
			(fill yes)
			(layer "F.Fab")
		)
		(fp_text user "7"
			(at 13.151866 -0.098806 0)
			(unlocked yes)
			(layer "F.SilkS")
			(effects
				(font
					(size 0.7874 0.5842)
					(thickness 0.1524)
				)
			)
		)
		(fp_text user "8"
			(at 13.051536 -2.872486 0)
			(unlocked yes)
			(layer "F.SilkS")
			(effects
				(font
					(size 0.7874 0.5842)
					(thickness 0.1524)
				)
			)
		)
		(fp_text user "2"
			(at -4.254754 -3.141218 0)
			(unlocked yes)
			(layer "F.SilkS")
			(effects
				(font
					(size 0.7874 0.5842)
					(thickness 0.1524)
				)
			)
		)
		(fp_text user "1"
			(at -4.45516 -0.935482 0)
			(unlocked yes)
			(layer "F.SilkS")
			(effects
				(font
					(size 0.7874 0.5842)
					(thickness 0.1524)
				)
			)
		)
		(fp_text user "8"
			(at 10.255504 -2.572766 0)
			(unlocked yes)
			(layer "B.SilkS")
			(effects
				(font
					(size 0.7874 0.5842)
					(thickness 0.1524)
				)
				(justify mirror)
			)
		)
		(fp_text user "7"
			(at 8.998204 -0.007366 0)
			(unlocked yes)
			(layer "B.SilkS")
			(effects
				(font
					(size 0.7874 0.5842)
					(thickness 0.1524)
				)
				(justify mirror)
			)
		)
		(fp_text user "2"
			(at 0.070104 -2.725166 0)
			(unlocked yes)
			(layer "B.SilkS")
			(effects
				(font
					(size 0.7874 0.5842)
					(thickness 0.1524)
				)
				(justify mirror)
			)
		)
		(fp_text user "1"
			(at -1.047496 -0.147066 0)
			(unlocked yes)
			(layer "B.SilkS")
			(effects
				(font
					(size 0.7874 0.5842)
					(thickness 0.1524)
				)
				(justify mirror)
			)
		)
		(fp_text user "8"
			(at 10.1219 -2.479548 180)
			(unlocked yes)
			(layer "B.Fab")
			(effects
				(font
					(size 0.7874 0.5842)
					(thickness 0.000001)
				)
				(justify mirror)
			)
		)
		(fp_text user "7"
			(at 8.8646 0.085852 180)
			(unlocked yes)
			(layer "B.Fab")
			(effects
				(font
					(size 0.7874 0.5842)
					(thickness 0.000001)
				)
				(justify mirror)
			)
		)
		(fp_text user "2"
			(at -0.0635 -2.631948 180)
			(unlocked yes)
			(layer "B.Fab")
			(effects
				(font
					(size 0.7874 0.5842)
					(thickness 0.000001)
				)
				(justify mirror)
			)
		)
		(fp_text user "1"
			(at -1.1811 -0.053848 180)
			(unlocked yes)
			(layer "B.Fab")
			(effects
				(font
					(size 0.7874 0.5842)
					(thickness 0.000001)
				)
				(justify mirror)
			)
		)
		(fp_text user "8"
			(at 13.2715 -2.593848 180)
			(unlocked yes)
			(layer "F.Fab")
			(effects
				(font
					(size 0.7874 0.5842)
					(thickness 0.000001)
				)
			)
		)
		(fp_text user "7"
			(at 13.2334 -0.079248 180)
			(unlocked yes)
			(layer "F.Fab")
			(effects
				(font
					(size 0.7874 0.5842)
					(thickness 0.000001)
				)
			)
		)
		(fp_text user "1"
			(at -4.4323 -1.019048 180)
			(unlocked yes)
			(layer "F.Fab")
			(effects
				(font
					(size 0.7874 0.5842)
					(thickness 0.000001)
				)
			)
		)
		(fp_text user "2"
			(at -4.4704 -2.581148 180)
			(unlocked yes)
			(layer "F.Fab")
			(effects
				(font
					(size 0.7874 0.5842)
					(thickness 0.000001)
				)
			)
		)
		(pad "" np_thru_hole circle
			(at -1.27 6.35 180)
			(size 3.2004 3.2004)
			(drill 3.2004)
			(layers "*.Cu" "*.Mask")
			(clearance 0.381)
			(thermal_gap 0.381)
		)
		(pad "" np_thru_hole circle
			(at 10.16 6.35 180)
			(size 3.2004 3.2004)
			(drill 3.2004)
			(layers "*.Cu" "*.Mask")
			(clearance 0.381)
			(thermal_gap 0.381)
		)
		(pad "1" thru_hole rect
			(at 0 0 180)
			(size 1.3208 1.3208)
			(drill 0.9144)
			(layers "*.Cu" "*.Mask")
			(remove_unused_layers no)
			(net "LAN1_P1_P")
			(clearance 0.0508)
			(thermal_gap 0.0508)
			(padstack
				(mode front_inner_back)
				(layer "Inner"
					(shape circle)
					(size 1.3208 1.3208)
					(clearance 0.0508)
				)
				(layer "B.Cu"
					(shape rect)
					(size 1.3208 1.3208)
					(clearance 0.0508)
				)
			)
		)
		(pad "2" thru_hole circle
			(at 1.27 -2.54 180)
			(size 1.3208 1.3208)
			(drill 0.9144)
			(layers "*.Cu" "*.Mask")
			(remove_unused_layers no)
			(net "LAN1_P1_N")
			(clearance 0.0508)
			(thermal_gap 0.0508)
		)
		(pad "3" thru_hole circle
			(at 2.54 0 180)
			(size 1.3208 1.3208)
			(drill 0.9144)
			(layers "*.Cu" "*.Mask")
			(remove_unused_layers no)
			(net "LAN1_P2_P")
			(clearance 0.0508)
			(thermal_gap 0.0508)
		)
		(pad "4" thru_hole circle
			(at 3.81 -2.54 180)
			(size 1.3208 1.3208)
			(drill 0.9144)
			(layers "*.Cu" "*.Mask")
			(remove_unused_layers no)
			(net "LAN1_P3_P")
			(clearance 0.0508)
			(thermal_gap 0.0508)
		)
		(pad "5" thru_hole circle
			(at 5.08 0 180)
			(size 1.3208 1.3208)
			(drill 0.9144)
			(layers "*.Cu" "*.Mask")
			(remove_unused_layers no)
			(net "LAN1_P3_N")
			(clearance 0.0508)
			(thermal_gap 0.0508)
		)
		(pad "6" thru_hole circle
			(at 6.35 -2.54 180)
			(size 1.3208 1.3208)
			(drill 0.9144)
			(layers "*.Cu" "*.Mask")
			(remove_unused_layers no)
			(net "LAN1_P2_N")
			(clearance 0.0508)
			(thermal_gap 0.0508)
		)
		(pad "7" thru_hole circle
			(at 7.62 0 180)
			(size 1.3208 1.3208)
			(drill 0.9144)
			(layers "*.Cu" "*.Mask")
			(remove_unused_layers no)
			(net "LAN1_P4_P")
			(clearance 0.0508)
			(thermal_gap 0.0508)
		)
		(pad "8" thru_hole circle
			(at 8.89 -2.54 180)
			(size 1.3208 1.3208)
			(drill 0.9144)
			(layers "*.Cu" "*.Mask")
			(remove_unused_layers no)
			(net "LAN1_P4_N")
			(clearance 0.0508)
			(thermal_gap 0.0508)
		)
		(pad "9" thru_hole circle
			(at -1.854962 10.459974 180)
			(size 1.3208 1.3208)
			(drill 0.9144)
			(layers "*.Cu" "*.Mask")
			(remove_unused_layers no)
			(net "N42126764")
			(clearance 0.0508)
			(thermal_gap 0.0508)
		)
		(pad "10" thru_hole circle
			(at 0.635 10.459974 180)
			(size 1.3208 1.3208)
			(drill 0.9144)
			(layers "*.Cu" "*.Mask")
			(remove_unused_layers no)
			(net "N42126673")
			(clearance 0.0508)
			(thermal_gap 0.0508)
		)
		(pad "11" thru_hole circle
			(at 8.255 10.459974 180)
			(size 1.3208 1.3208)
			(drill 0.9144)
			(layers "*.Cu" "*.Mask")
			(remove_unused_layers no)
			(net "Net_424")
			(clearance 0.0508)
			(thermal_gap 0.0508)
		)
		(pad "12" thru_hole circle
			(at 10.744962 10.459974 180)
			(size 1.3208 1.3208)
			(drill 0.9144)
			(layers "*.Cu" "*.Mask")
			(remove_unused_layers no)
			(net "N42130542")
			(clearance 0.0508)
			(thermal_gap 0.0508)
		)
		(pad "G1" thru_hole circle
			(at -3.430016 2.500122 180)
			(size 2.3622 2.3622)
			(drill 1.6002)
			(layers "*.Cu" "*.Mask")
			(remove_unused_layers no)
			(net "GND")
			(clearance -0.127)
		)
		(pad "G2" thru_hole circle
			(at 12.320016 2.500122 180)
			(size 2.3622 2.3622)
			(drill 1.6002)
			(layers "*.Cu" "*.Mask")
			(remove_unused_layers no)
			(net "GND")
			(clearance -0.127)
		)
		(zone
			(layers "F.Cu" "B.Cu" "In1.Cu" "In2.Cu" "In3.Cu" "In4.Cu" "In5.Cu" "In6.Cu")
			(hatch none 0.5)
			(connect_pads
				(clearance 0)
			)
			(min_thickness 0.25)
			(keepout
				(tracks not_allowed)
				(vias allowed)
				(pads allowed)
				(copperpour not_allowed)
				(footprints allowed)
			)
			(placement
				(enabled no)
				(sheetname "")
			)
			(fill
				(thermal_gap 0.5)
				(thermal_bridge_width 0.5)
				(island_removal_mode 0)
			)
			(polygon
				(pts
					(arc
						(start 5.56133 -138.100054)
						(mid 1.54813 -138.100054)
						(end 5.56133 -138.100054)
					)
				)
			)
		)
		(zone
			(layers "F.Cu" "B.Cu" "In1.Cu" "In2.Cu" "In3.Cu" "In4.Cu" "In5.Cu" "In6.Cu")
			(hatch none 0.5)
			(connect_pads
				(clearance 0)
			)
			(min_thickness 0.25)
			(keepout
				(tracks not_allowed)
				(vias allowed)
				(pads allowed)
				(copperpour not_allowed)
				(footprints allowed)
			)
			(placement
				(enabled no)
				(sheetname "")
			)
			(fill
				(thermal_gap 0.5)
				(thermal_bridge_width 0.5)
				(island_removal_mode 0)
			)
			(polygon
				(pts
					(arc
						(start 16.99133 -138.100054)
						(mid 12.97813 -138.100054)
						(end 16.99133 -138.100054)
					)
				)
			)
		)
	)
	(footprint ""
		(layer "F.Cu")
		(at 27.640026 -462.229962 -90)
		(property "Reference" "R101"
			(at -1.317752 1.035304 90)
			(unlocked yes)
			(layer "F.SilkS")
			(effects
				(font
					(size 0.7874 0.5842)
					(thickness 0.1524)
				)
				(justify left)
			)
		)
		(property "Value" ""
			(at 0 0 270)
			(layer "F.Fab")
			(effects
				(font
					(size 1.27 1.27)
				)
			)
		)
		(duplicate_pad_numbers_are_jumpers no)
		(fp_line
			(start -0.7874 0.4064)
			(end -0.7874 -0.4064)
			(stroke
				(width 0.1524)
				(type default)
			)
			(layer "F.SilkS")
		)
		(fp_line
			(start 0.7874 0.4064)
			(end -0.7874 0.4064)
			(stroke
				(width 0.1524)
				(type default)
			)
			(layer "F.SilkS")
		)
		(fp_line
			(start -0.7874 -0.4064)
			(end 0.7874 -0.4064)
			(stroke
				(width 0.1524)
				(type default)
			)
			(layer "F.SilkS")
		)
		(fp_line
			(start 0.7874 -0.4064)
			(end 0.7874 0.4064)
			(stroke
				(width 0.1524)
				(type default)
			)
			(layer "F.SilkS")
		)
		(fp_poly
			(pts
				(xy -0.508 0.2794) (xy -0.508 0.2286) (xy -0.635 0.2286) (xy -0.635 -0.254) (xy -0.5334 -0.254)
				(xy -0.5334 -0.2794) (xy 0.5334 -0.2794) (xy 0.5334 -0.254) (xy 0.635 -0.254) (xy 0.635 0.254) (xy 0.5334 0.254)
				(xy 0.5334 0.2794)
			)
			(stroke
				(width 0)
				(type default)
			)
			(fill no)
			(layer "F.CrtYd")
		)
		(pad "1" smd rect
			(at 0.40005 0 270)
			(size 0.4572 0.508)
			(layers "F.Cu" "F.Mask" "F.Paste")
			(net "PSU6_REMOTE_N")
		)
		(pad "2" smd rect
			(at -0.40005 0 270)
			(size 0.4572 0.508)
			(layers "F.Cu" "F.Mask" "F.Paste")
			(net "PSU6_REMOTE_R_N")
		)
	)
	(footprint ""
		(layer "F.Cu")
		(at 2.439924 -152.374854 90)
		(property "Reference" "J33"
			(at -1.582928 4.743704 90)
			(unlocked yes)
			(layer "F.SilkS")
			(effects
				(font
					(size 0.7874 0.5842)
					(thickness 0.1524)
				)
				(justify left)
			)
		)
		(property "Value" ""
			(at 0 0 90)
			(layer "F.Fab")
			(effects
				(font
					(size 1.27 1.27)
				)
			)
		)
		(duplicate_pad_numbers_are_jumpers no)
		(fp_line
			(start 1.849882 -1.999996)
			(end -3.02006 -1.999996)
			(stroke
				(width 0.1524)
				(type default)
			)
			(layer "F.SilkS")
		)
		(fp_line
			(start -3.02006 -1.999996)
			(end -3.02006 3.999992)
			(stroke
				(width 0.1524)
				(type default)
			)
			(layer "F.SilkS")
		)
		(fp_line
			(start 1.35001 -1.500124)
			(end -2.519934 -1.500124)
			(stroke
				(width 0.1524)
				(type default)
			)
			(layer "F.SilkS")
		)
		(fp_line
			(start -2.519934 -1.500124)
			(end -2.519934 3.50012)
			(stroke
				(width 0.1524)
				(type default)
			)
			(layer "F.SilkS")
		)
		(fp_line
			(start 1.849882 0.500126)
			(end 1.35001 0.500126)
			(stroke
				(width 0.1524)
				(type default)
			)
			(layer "F.SilkS")
		)
		(fp_line
			(start 1.35001 0.500126)
			(end 1.35001 -1.500124)
			(stroke
				(width 0.1524)
				(type default)
			)
			(layer "F.SilkS")
		)
		(fp_line
			(start 1.35001 1.500124)
			(end 1.849882 1.500124)
			(stroke
				(width 0.1524)
				(type default)
			)
			(layer "F.SilkS")
		)
		(fp_line
			(start 1.35001 3.50012)
			(end 1.35001 1.500124)
			(stroke
				(width 0.1524)
				(type default)
			)
			(layer "F.SilkS")
		)
		(fp_line
			(start -2.519934 3.50012)
			(end 1.35001 3.50012)
			(stroke
				(width 0.1524)
				(type default)
			)
			(layer "F.SilkS")
		)
		(fp_line
			(start 1.849882 3.999992)
			(end 1.849882 -1.999996)
			(stroke
				(width 0.1524)
				(type default)
			)
			(layer "F.SilkS")
		)
		(fp_line
			(start -3.02006 3.999992)
			(end 1.849882 3.999992)
			(stroke
				(width 0.1524)
				(type default)
			)
			(layer "F.SilkS")
		)
		(fp_poly
			(pts
				(xy 2.01041 0) (xy 3.06959 -0.52959) (xy 3.06959 0.52959)
			)
			(stroke
				(width 0)
				(type default)
			)
			(fill yes)
			(layer "F.SilkS")
		)
		(fp_poly
			(pts
				(xy -0.8382 2.8194) (xy 0.8382 2.8194) (xy 0.8382 -0.8382) (xy -0.8382 -0.8382)
			)
			(stroke
				(width 0)
				(type default)
			)
			(fill no)
			(layer "B.CrtYd")
		)
		(fp_poly
			(pts
				(xy -3.02006 3.999992) (xy 1.849882 3.999992) (xy 1.849882 -1.999996) (xy -3.02006 -1.999996)
			)
			(stroke
				(width 0)
				(type default)
			)
			(fill no)
			(layer "F.CrtYd")
		)
		(fp_line
			(start 1.849882 -1.999996)
			(end -3.02006 -1.999996)
			(stroke
				(width 0.1)
				(type default)
			)
			(layer "F.Fab")
		)
		(fp_line
			(start -3.02006 -1.999996)
			(end -3.02006 3.999992)
			(stroke
				(width 0.1)
				(type default)
			)
			(layer "F.Fab")
		)
		(fp_line
			(start 1.849882 3.999992)
			(end 1.849882 -1.999996)
			(stroke
				(width 0.1)
				(type default)
			)
			(layer "F.Fab")
		)
		(fp_line
			(start -3.02006 3.999992)
			(end 1.849882 3.999992)
			(stroke
				(width 0.1)
				(type default)
			)
			(layer "F.Fab")
		)
		(fp_poly
			(pts
				(xy 2.01041 0) (xy 3.06959 -0.52959) (xy 3.06959 0.52959)
			)
			(stroke
				(width 0)
				(type default)
			)
			(fill yes)
			(layer "F.Fab")
		)
		(fp_text user "2"
			(at 2.5527 2.16535 90)
			(unlocked yes)
			(layer "F.SilkS")
			(effects
				(font
					(size 0.7874 0.5842)
					(thickness 0.1524)
				)
			)
		)
		(fp_text user "1"
			(at 1.2192 0.00127 90)
			(unlocked yes)
			(layer "B.SilkS")
			(effects
				(font
					(size 0.7874 0.5842)
					(thickness 0.1524)
				)
				(justify mirror)
			)
		)
		(fp_text user "2"
			(at 1.2192 2.001266 90)
			(unlocked yes)
			(layer "B.SilkS")
			(effects
				(font
					(size 0.7874 0.5842)
					(thickness 0.1524)
				)
				(justify mirror)
			)
		)
		(fp_text user "1"
			(at 1.2192 0.00127 90)
			(unlocked yes)
			(layer "B.Fab")
			(effects
				(font
					(size 0.7874 0.5842)
					(thickness 0.1524)
				)
				(justify mirror)
			)
		)
		(fp_text user "2"
			(at 1.2192 2.001266 90)
			(unlocked yes)
			(layer "B.Fab")
			(effects
				(font
					(size 0.7874 0.5842)
					(thickness 0.1524)
				)
				(justify mirror)
			)
		)
		(fp_text user "2"
			(at 2.5527 2.16535 90)
			(unlocked yes)
			(layer "F.Fab")
			(effects
				(font
					(size 0.7874 0.5842)
					(thickness 0.1524)
				)
			)
		)
		(pad "1" thru_hole rect
			(at 0 0 90)
			(size 1.524 1.524)
			(drill 1.016)
			(layers "*.Cu" "*.Mask")
			(remove_unused_layers no)
			(net "CM_PWR_CTL_IN")
			(clearance 0)
			(padstack
				(mode front_inner_back)
				(layer "Inner"
					(shape circle)
					(size 1.524 1.524)
					(clearance 0)
				)
				(layer "B.Cu"
					(shape rect)
					(size 1.524 1.524)
					(clearance 0)
				)
			)
		)
		(pad "2" thru_hole circle
			(at 0 1.999996 90)
			(size 1.524 1.524)
			(drill 1.016)
			(layers "*.Cu" "*.Mask")
			(remove_unused_layers no)
			(net "GND")
			(clearance 0)
		)
	)
)
